FILE_TYPE = CONNECTIVITY;
{Allegro Design Entry HDL 17.4-2019 S026 (4007227) 1/17/2022}
"PAGE_NUMBER" = 135;
0"NC";
END.
